# T6G (Grand Teton) — schematic netlist excerpt (pin names and nets, part order shuffled) for the footprints in the layout excerpt that follows; sources: Cadence DE-HDL packaged netlist, KiCad conversion of 04192023_DAF0TMB3IC0_F0TG_MB_C_brd_V02_OCP.brd

R706  Q_RES  4.7K 5% EMPTY  pkg 0201LF  page 320 : A = P1V8_CPU1_RT_1D ; B = GPIO2_RT_CPU1_P0
PC190  Q_CAP  560PF 50V 10% EMPTY  pkg C0402  page 201 : A = SW_PVDDCR_CPU1_P0_SW2 ; B = SW_PVDDCR_CPU1_P0_SW2_RC
R979  Q_RES  10K 1% CHIP  pkg 0201LF  page 276 : A = GPIO2_RT_CPU0_P0 ; B = GND

(kicad_pcb
	(version 20260206)
	(generator "pcbnew")
	(generator_version "10.0")
	(general
		(thickness 1.6)
		(legacy_teardrops no)
	)
	(paper "A4")
	(title_block
		(title "04192023_DAF0TMB3IC0_F0TG_MB_C_brd_V02_OCP.brd")
		(comment 1 "Grand Teton / footprints 2008-2010 of 8354")
	)
	(layers
		(0 "F.Cu" signal "TOP")
		(4 "In1.Cu" signal "GND")
		(6 "In2.Cu" signal "IN1")
		(8 "In3.Cu" signal "GND1")
		(10 "In4.Cu" signal "IN2")
		(12 "In5.Cu" signal "GND2")
		(14 "In6.Cu" signal "IN3")
		(16 "In7.Cu" signal "GND3")
		(18 "In8.Cu" signal "VCC")
		(20 "In9.Cu" signal "VCC1")
		(22 "In10.Cu" signal "GND4")
		(24 "In11.Cu" signal "IN4")
		(26 "In12.Cu" signal "GND5")
		(28 "In13.Cu" signal "IN5")
		(30 "In14.Cu" signal "GND6")
		(32 "In15.Cu" signal "IN6")
		(34 "In16.Cu" signal "GND7")
		(2 "B.Cu" signal "BOTTOM")
		(9 "F.Adhes" user "F.Adhesive")
		(11 "B.Adhes" user "B.Adhesive")
		(13 "F.Paste" user "Package Geometry/Pastemask Top")
		(15 "B.Paste" user "Package Geometry/Pastemask Bottom")
		(5 "F.SilkS" user "Ref Des/Silkscreen Top")
		(7 "B.SilkS" user "Ref Des/Silkscreen Bottom")
		(1 "F.Mask" user "Board Geometry/Soldermask Top")
		(3 "B.Mask" user "Board Geometry/Soldermask Bottom")
		(17 "Dwgs.User" user "User.Drawings")
		(19 "Cmts.User" user "User.Comments")
		(21 "Eco1.User" user "User.Eco1")
		(23 "Eco2.User" user "User.Eco2")
		(25 "Edge.Cuts" user "Board Geometry/Outline")
		(27 "Margin" user)
		(31 "F.CrtYd" user "Package Geometry/Place Bound Top")
		(29 "B.CrtYd" user "Package Geometry/Place Bound Bottom")
		(35 "F.Fab" user "Ref Des/Assembly Top")
		(33 "B.Fab" user "Ref Des/Assembly Bottom")
	)
	(footprint ""
		(layer "F.Cu")
		(at 299.265594 -393.96416)
		(property "Reference" "R979"
			(at 0 0 0)
			(layer "F.SilkS")
			(hide yes)
			(effects
				(font
					(size 1.27 1.27)
				)
			)
		)
		(property "Value" ""
			(at 0 0 0)
			(layer "F.Fab")
			(effects
				(font
					(size 1.27 1.27)
				)
			)
		)
		(duplicate_pad_numbers_are_jumpers no)
		(fp_line
			(start -0.32512 -0.175006)
			(end 0.32512 -0.175006)
			(stroke
				(width 0.1)
				(type default)
			)
			(layer "F.Fab")
		)
		(fp_line
			(start -0.32512 0.175006)
			(end -0.32512 -0.175006)
			(stroke
				(width 0.1)
				(type default)
			)
			(layer "F.Fab")
		)
		(fp_line
			(start 0.32512 -0.175006)
			(end 0.32512 0.175006)
			(stroke
				(width 0.1)
				(type default)
			)
			(layer "F.Fab")
		)
		(fp_line
			(start 0.32512 0.175006)
			(end -0.32512 0.175006)
			(stroke
				(width 0.1)
				(type default)
			)
			(layer "F.Fab")
		)
		(pad "1" smd rect
			(at -0.2667 0)
			(size 0.3048 0.381)
			(layers "F.Cu" "F.Mask" "F.Paste")
			(net "GPIO2_RT_CPU0_P0")
		)
		(pad "2" smd rect
			(at 0.2667 0 180)
			(size 0.3048 0.381)
			(layers "F.Cu" "F.Mask" "F.Paste")
			(net "GND")
		)
	)
	(footprint ""
		(layer "F.Cu")
		(at 41.995852 -385.58216)
		(property "Reference" "R706"
			(at 0 0 0)
			(layer "F.SilkS")
			(hide yes)
			(effects
				(font
					(size 1.27 1.27)
				)
			)
		)
		(property "Value" ""
			(at 0 0 0)
			(layer "F.Fab")
			(effects
				(font
					(size 1.27 1.27)
				)
			)
		)
		(duplicate_pad_numbers_are_jumpers no)
		(fp_line
			(start -0.32512 -0.175006)
			(end 0.32512 -0.175006)
			(stroke
				(width 0.1)
				(type default)
			)
			(layer "F.Fab")
		)
		(fp_line
			(start -0.32512 0.175006)
			(end -0.32512 -0.175006)
			(stroke
				(width 0.1)
				(type default)
			)
			(layer "F.Fab")
		)
		(fp_line
			(start 0.32512 -0.175006)
			(end 0.32512 0.175006)
			(stroke
				(width 0.1)
				(type default)
			)
			(layer "F.Fab")
		)
		(fp_line
			(start 0.32512 0.175006)
			(end -0.32512 0.175006)
			(stroke
				(width 0.1)
				(type default)
			)
			(layer "F.Fab")
		)
		(pad "1" smd rect
			(at -0.2667 0)
			(size 0.3048 0.381)
			(layers "F.Cu" "F.Mask" "F.Paste")
			(net "P1V8_CPU1_RT_1D")
		)
		(pad "2" smd rect
			(at 0.2667 0 180)
			(size 0.3048 0.381)
			(layers "F.Cu" "F.Mask" "F.Paste")
			(net "GPIO2_RT_CPU1_P0")
		)
	)
	(footprint ""
		(layer "F.Cu")
		(at 323.007482 -331.983842 180)
		(property "Reference" "PC190"
			(at 0 0 180)
			(layer "F.SilkS")
			(hide yes)
			(effects
				(font
					(size 1.27 1.27)
				)
			)
		)
		(property "Value" ""
			(at 0 0 180)
			(layer "F.Fab")
			(effects
				(font
					(size 1.27 1.27)
				)
			)
		)
		(duplicate_pad_numbers_are_jumpers no)
		(fp_line
			(start 0.7874 0.4064)
			(end -0.7874 0.4064)
			(stroke
				(width 0.1524)
				(type default)
			)
			(layer "F.SilkS")
		)
		(fp_line
			(start 0.7874 -0.4064)
			(end 0.7874 0.4064)
			(stroke
				(width 0.1524)
				(type default)
			)
			(layer "F.SilkS")
		)
		(fp_line
			(start -0.7874 0.4064)
			(end -0.7874 -0.4064)
			(stroke
				(width 0.1524)
				(type default)
			)
			(layer "F.SilkS")
		)
		(fp_line
			(start -0.7874 -0.4064)
			(end 0.7874 -0.4064)
			(stroke
				(width 0.1524)
				(type default)
			)
			(layer "F.SilkS")
		)
		(fp_line
			(start 0.67945 0.3048)
			(end 0.120396 0.3048)
			(stroke
				(width 0.1)
				(type default)
			)
			(layer "F.Fab")
		)
		(fp_line
			(start 0.67945 -0.3048)
			(end 0.67945 0.3048)
			(stroke
				(width 0.1)
				(type default)
			)
			(layer "F.Fab")
		)
		(fp_line
			(start 0.12065 -0.2794)
			(end 0.12065 -0.3048)
			(stroke
				(width 0.1)
				(type default)
			)
			(layer "F.Fab")
		)
		(fp_line
			(start 0.12065 -0.3048)
			(end 0.67945 -0.3048)
			(stroke
				(width 0.1)
				(type default)
			)
			(layer "F.Fab")
		)
		(fp_line
			(start 0.120396 0.3048)
			(end 0.120396 0.2794)
			(stroke
				(width 0.1)
				(type default)
			)
			(layer "F.Fab")
		)
		(fp_line
			(start 0.120396 0.2794)
			(end -0.12065 0.2794)
			(stroke
				(width 0.1)
				(type default)
			)
			(layer "F.Fab")
		)
		(fp_line
			(start -0.12065 0.3048)
			(end -0.67945 0.3048)
			(stroke
				(width 0.1)
				(type default)
			)
			(layer "F.Fab")
		)
		(fp_line
			(start -0.12065 0.2794)
			(end -0.12065 0.3048)
			(stroke
				(width 0.1)
				(type default)
			)
			(layer "F.Fab")
		)
		(fp_line
			(start -0.12065 -0.2794)
			(end 0.12065 -0.2794)
			(stroke
				(width 0.1)
				(type default)
			)
			(layer "F.Fab")
		)
		(fp_line
			(start -0.12065 -0.305054)
			(end -0.12065 -0.2794)
			(stroke
				(width 0.1)
				(type default)
			)
			(layer "F.Fab")
		)
		(fp_line
			(start -0.67945 0.3048)
			(end -0.67945 -0.305054)
			(stroke
				(width 0.1)
				(type default)
			)
			(layer "F.Fab")
		)
		(fp_line
			(start -0.67945 -0.305054)
			(end -0.12065 -0.305054)
			(stroke
				(width 0.1)
				(type default)
			)
			(layer "F.Fab")
		)
		(pad "1" smd circle
			(at -0.40005 0 180)
			(size 0 0)
			(layers "F.Cu" "F.Mask" "F.Paste")
			(net "SW_PVDDCR_CPU1_P0_SW2")
		)
		(pad "2" smd circle
			(at 0.40005 0 180)
			(size 0 0)
			(layers "F.Cu" "F.Mask" "F.Paste")
			(net "SW_PVDDCR_CPU1_P0_SW2_RC")
		)
	)
)
